FILE_TYPE=LIBRARY_PARTS;
TIME=' Created/Modified on Thu Feb 10 11:12:39 2011' ;
primitive 'TP_TDR_4P_FTS';
  pin
    'P1':
      PIN_NUMBER='(2)';
      INPUT_LOAD='(-0.01,0.01)';
      OUTPUT_LOAD='(1.0,-1.0)';
      BIDIRECTIONAL='TRUE';
    'P2':
      PIN_NUMBER='(3)';
      INPUT_LOAD='(-0.01,0.01)';
      OUTPUT_LOAD='(1.0,-1.0)';
      BIDIRECTIONAL='TRUE';
    'S1':
      PIN_NUMBER='(1)';
      INPUT_LOAD='(-0.01,0.01)';
      OUTPUT_LOAD='(1.0,-1.0)';
      BIDIRECTIONAL='TRUE';
    'S2':
      PIN_NUMBER='(4)';
      INPUT_LOAD='(-0.01,0.01)';
      OUTPUT_LOAD='(1.0,-1.0)';
      BIDIRECTIONAL='TRUE';
  end_pin;
  body
    CLASS='DISCRETE';
    PART_NAME='TP_TDR_4P_FTS';
    PHYS_DES_PREFIX='X';
  end_body;
end_primitive;
END.
